(kicad_pcb
	(version 20260206)
	(generator "pcbnew")
	(generator_version "10.0")
	(general
		(thickness 1.6)
		(legacy_teardrops no)
	)
	(paper "A4")
	(title_block
		(title "Bryce Canyon_F.DPB_16315-1-OCP.brd")
		(comment 1 "Bryce Canyon / footprints 1352-1358 of 2223")
	)
	(layers
		(0 "F.Cu" signal "TOP")
		(4 "In1.Cu" signal "L2GND")
		(6 "In2.Cu" signal "L3")
		(8 "In3.Cu" signal "L4GND")
		(10 "In4.Cu" signal "L5")
		(12 "In5.Cu" signal "L6VCC")
		(14 "In6.Cu" signal "L7VCC")
		(16 "In7.Cu" signal "L8")
		(18 "In8.Cu" signal "L9GND")
		(20 "In9.Cu" signal "L10")
		(22 "In10.Cu" signal "L11GND")
		(2 "B.Cu" signal "BOTTOM")
		(9 "F.Adhes" user "F.Adhesive")
		(11 "B.Adhes" user "B.Adhesive")
		(13 "F.Paste" user "Package Geometry/Pastemask Top")
		(15 "B.Paste" user "Package Geometry/Pastemask Bottom")
		(5 "F.SilkS" user "Ref Des/Silkscreen Top")
		(7 "B.SilkS" user "Ref Des/Silkscreen Bottom")
		(1 "F.Mask" user "Board Geometry/Soldermask Top")
		(3 "B.Mask" user "Board Geometry/Soldermask Bottom")
		(17 "Dwgs.User" user "User.Drawings")
		(19 "Cmts.User" user "User.Comments")
		(21 "Eco1.User" user "User.Eco1")
		(23 "Eco2.User" user "User.Eco2")
		(25 "Edge.Cuts" user "Board Geometry/Outline")
		(27 "Margin" user)
		(31 "F.CrtYd" user "Package Geometry/Place Bound Top")
		(29 "B.CrtYd" user "Package Geometry/Place Bound Bottom")
		(35 "F.Fab" user "Ref Des/Assembly Top")
		(33 "B.Fab" user "Ref Des/Assembly Bottom")
	)
	(footprint ""
		(layer "F.Cu")
		(at 461.0735 -272.535142 180)
		(property "Reference" "R372"
			(at 0 0 180)
			(layer "F.SilkS")
			(hide yes)
			(effects
				(font
					(size 1.27 1.27)
				)
			)
		)
		(property "Value" "0R2J-2-GP"
			(at 0.064008 -3.993896 180)
			(unlocked yes)
			(layer "F.Fab")
			(hide yes)
			(effects
				(font
					(size 1.016 1.016)
					(thickness 0.1524)
				)
			)
		)
		(property "Device Type" "R402H16"
			(at 0.064008 -5.517896 180)
			(unlocked yes)
			(layer "F.Fab")
			(hide yes)
			(effects
				(font
					(size 1.016 1.016)
					(thickness 0.1524)
				)
			)
		)
		(duplicate_pad_numbers_are_jumpers no)
		(fp_line
			(start 0.508 -0.9398)
			(end -0.508 -0.9398)
			(stroke
				(width 0.1524)
				(type default)
			)
			(layer "F.SilkS")
		)
		(fp_line
			(start -0.508 -0.9398)
			(end -0.508 0.9398)
			(stroke
				(width 0.1524)
				(type default)
			)
			(layer "F.SilkS")
		)
		(fp_rect
			(start -0.508 0.9398)
			(end 0.508 -0.9398)
			(stroke
				(width 0)
				(type default)
			)
			(fill no)
			(layer "F.CrtYd")
		)
		(fp_rect
			(start -0.508 0.9398)
			(end 0.508 -0.9398)
			(stroke
				(width 0)
				(type default)
			)
			(fill no)
			(layer "F.Fab")
		)
		(pad "1" smd custom
			(at 0 -0.4445 180)
			(size 0.1397 0.1397)
			(layers "F.Cu" "F.Mask" "F.Paste")
			(net "DRIVE_A_10_PWR")
			(options
				(clearance outline)
				(anchor circle)
			)
			(primitives
				(gr_poly
					(pts
						(arc
							(start -0.1778 -0.2794)
							(mid -0.249642 -0.249642)
							(end -0.2794 -0.1778)
						)
						(arc
							(start -0.2794 0.1778)
							(mid -0.249642 0.249642)
							(end -0.1778 0.2794)
						)
						(arc
							(start 0.1778 0.2794)
							(mid 0.249642 0.249642)
							(end 0.2794 0.1778)
						)
						(arc
							(start 0.2794 -0.1778)
							(mid 0.249642 -0.249642)
							(end 0.1778 -0.2794)
						)
					)
					(width 0)
					(fill yes)
				)
			)
		)
		(pad "2" smd custom
			(at 0 0.4445 180)
			(size 0.1397 0.1397)
			(layers "F.Cu" "F.Mask" "F.Paste")
			(net "SW_PWR_R_HDD10")
			(options
				(clearance outline)
				(anchor circle)
			)
			(primitives
				(gr_poly
					(pts
						(arc
							(start -0.1778 -0.2794)
							(mid -0.249642 -0.249642)
							(end -0.2794 -0.1778)
						)
						(arc
							(start -0.2794 0.1778)
							(mid -0.249642 0.249642)
							(end -0.1778 0.2794)
						)
						(arc
							(start 0.1778 0.2794)
							(mid 0.249642 0.249642)
							(end 0.2794 0.1778)
						)
						(arc
							(start 0.2794 -0.1778)
							(mid 0.249642 -0.249642)
							(end 0.1778 -0.2794)
						)
					)
					(width 0)
					(fill yes)
				)
			)
		)
	)
	(footprint ""
		(layer "F.Cu")
		(at 365.16691 -184.40527 -90)
		(property "Reference" "R568"
			(at 0 0 270)
			(layer "F.SilkS")
			(hide yes)
			(effects
				(font
					(size 1.27 1.27)
				)
			)
		)
		(property "Value" "2R6F-GP"
			(at -0.0508 -4.8514 270)
			(unlocked yes)
			(layer "F.Fab")
			(hide yes)
			(effects
				(font
					(size 1.016 1.016)
					(thickness 0.1524)
				)
			)
		)
		(property "Device Type" "R1206H26"
			(at 0 -6.3754 270)
			(unlocked yes)
			(layer "F.Fab")
			(hide yes)
			(effects
				(font
					(size 1.016 1.016)
					(thickness 0.1524)
				)
			)
		)
		(duplicate_pad_numbers_are_jumpers no)
		(fp_line
			(start -1.016 2.2352)
			(end -1.016 -2.2352)
			(stroke
				(width 0.1524)
				(type default)
			)
			(layer "F.SilkS")
		)
		(fp_line
			(start 1.016 2.2352)
			(end -1.016 2.2352)
			(stroke
				(width 0.1524)
				(type default)
			)
			(layer "F.SilkS")
		)
		(fp_line
			(start -1.016 -2.2352)
			(end 1.016 -2.2352)
			(stroke
				(width 0.1524)
				(type default)
			)
			(layer "F.SilkS")
		)
		(fp_line
			(start 1.016 -2.2352)
			(end 1.016 2.2352)
			(stroke
				(width 0.1524)
				(type default)
			)
			(layer "F.SilkS")
		)
		(fp_rect
			(start -1.0922 2.3114)
			(end 1.0922 -2.3114)
			(stroke
				(width 0)
				(type default)
			)
			(fill no)
			(layer "F.CrtYd")
		)
		(fp_poly
			(pts
				(xy -1.0922 -2.3114) (xy 1.0922 -2.3114) (xy 1.0922 2.3114) (xy -1.0922 2.3114)
			)
			(stroke
				(width 0)
				(type default)
			)
			(fill no)
			(layer "F.Fab")
		)
		(pad "1" smd rect
			(at 0 -1.397 270)
			(size 1.651 1.27)
			(layers "F.Cu" "F.Mask" "F.Paste")
			(net "P12V_HDD19")
		)
		(pad "2" smd rect
			(at 0 1.397 270)
			(size 1.651 1.27)
			(layers "F.Cu" "F.Mask" "F.Paste")
			(net "12V_PRE_19")
		)
	)
	(footprint ""
		(layer "F.Cu")
		(at 284.353 -284.5308 180)
		(property "Reference" "R123"
			(at 0 0 180)
			(layer "F.SilkS")
			(hide yes)
			(effects
				(font
					(size 1.27 1.27)
				)
			)
		)
		(property "Value" "0R2J-2-GP"
			(at 0.064008 -3.993896 180)
			(unlocked yes)
			(layer "F.Fab")
			(hide yes)
			(effects
				(font
					(size 1.016 1.016)
					(thickness 0.1524)
				)
			)
		)
		(property "Device Type" "R402H16"
			(at 0.064008 -5.517896 180)
			(unlocked yes)
			(layer "F.Fab")
			(hide yes)
			(effects
				(font
					(size 1.016 1.016)
					(thickness 0.1524)
				)
			)
		)
		(duplicate_pad_numbers_are_jumpers no)
		(fp_line
			(start 0.508 -0.9398)
			(end -0.508 -0.9398)
			(stroke
				(width 0.1524)
				(type default)
			)
			(layer "F.SilkS")
		)
		(fp_line
			(start -0.508 -0.9398)
			(end -0.508 0.9398)
			(stroke
				(width 0.1524)
				(type default)
			)
			(layer "F.SilkS")
		)
		(fp_rect
			(start -0.508 0.9398)
			(end 0.508 -0.9398)
			(stroke
				(width 0)
				(type default)
			)
			(fill no)
			(layer "F.CrtYd")
		)
		(fp_rect
			(start -0.508 0.9398)
			(end 0.508 -0.9398)
			(stroke
				(width 0)
				(type default)
			)
			(fill no)
			(layer "F.Fab")
		)
		(pad "1" smd custom
			(at 0 -0.4445 180)
			(size 0.1397 0.1397)
			(layers "F.Cu" "F.Mask" "F.Paste")
			(net "IO_EXP2_LED_SCL")
			(options
				(clearance outline)
				(anchor circle)
			)
			(primitives
				(gr_poly
					(pts
						(arc
							(start -0.1778 -0.2794)
							(mid -0.249642 -0.249642)
							(end -0.2794 -0.1778)
						)
						(arc
							(start -0.2794 0.1778)
							(mid -0.249642 0.249642)
							(end -0.1778 0.2794)
						)
						(arc
							(start 0.1778 0.2794)
							(mid 0.249642 0.249642)
							(end 0.2794 0.1778)
						)
						(arc
							(start 0.2794 -0.1778)
							(mid 0.249642 -0.249642)
							(end 0.1778 -0.2794)
						)
					)
					(width 0)
					(fill yes)
				)
			)
		)
		(pad "2" smd custom
			(at 0 0.4445 180)
			(size 0.1397 0.1397)
			(layers "F.Cu" "F.Mask" "F.Paste")
			(net "I2C_DRIVE_A_FLT_LED_SCL")
			(options
				(clearance outline)
				(anchor circle)
			)
			(primitives
				(gr_poly
					(pts
						(arc
							(start -0.1778 -0.2794)
							(mid -0.249642 -0.249642)
							(end -0.2794 -0.1778)
						)
						(arc
							(start -0.2794 0.1778)
							(mid -0.249642 0.249642)
							(end -0.1778 0.2794)
						)
						(arc
							(start 0.1778 0.2794)
							(mid 0.249642 0.249642)
							(end 0.2794 0.1778)
						)
						(arc
							(start 0.2794 -0.1778)
							(mid 0.249642 -0.249642)
							(end 0.1778 -0.2794)
						)
					)
					(width 0)
					(fill yes)
				)
			)
		)
	)
	(footprint ""
		(layer "F.Cu")
		(at 49.964848 -127.254)
		(property "Reference" "R288"
			(at 0 0 0)
			(layer "F.SilkS")
			(hide yes)
			(effects
				(font
					(size 1.27 1.27)
				)
			)
		)
		(property "Value" "91R3F-1-GP"
			(at -0.0254 -2.5146 0)
			(unlocked yes)
			(layer "F.Fab")
			(hide yes)
			(effects
				(font
					(size 1.016 1.016)
					(thickness 0.1524)
				)
			)
		)
		(property "Device Type" "R603H22"
			(at -0.0254 -4.0386 0)
			(unlocked yes)
			(layer "F.Fab")
			(hide yes)
			(effects
				(font
					(size 1.016 1.016)
					(thickness 0.1524)
				)
			)
		)
		(duplicate_pad_numbers_are_jumpers no)
		(fp_line
			(start -0.4826 0)
			(end -0.2032 0)
			(stroke
				(width 0.2032)
				(type default)
			)
			(layer "F.SilkS")
		)
		(fp_line
			(start 0.2032 0)
			(end 0.4826 0)
			(stroke
				(width 0.2032)
				(type default)
			)
			(layer "F.SilkS")
		)
		(fp_rect
			(start -0.5842 1.3335)
			(end 0.5842 -1.3335)
			(stroke
				(width 0)
				(type default)
			)
			(fill no)
			(layer "F.CrtYd")
		)
		(fp_rect
			(start -0.5842 1.3335)
			(end 0.5842 -1.3335)
			(stroke
				(width 0)
				(type default)
			)
			(fill no)
			(layer "F.Fab")
		)
		(pad "1" smd custom
			(at 0 -0.762)
			(size 0.2159 0.2159)
			(layers "F.Cu" "F.Mask" "F.Paste")
			(net "P5V_A_1")
			(options
				(clearance outline)
				(anchor circle)
			)
			(primitives
				(gr_poly
					(pts
						(arc
							(start -0.3302 -0.4318)
							(mid -0.402042 -0.402042)
							(end -0.4318 -0.3302)
						)
						(arc
							(start -0.4318 0.3302)
							(mid -0.402042 0.402042)
							(end -0.3302 0.4318)
						)
						(arc
							(start 0.3302 0.4318)
							(mid 0.402042 0.402042)
							(end 0.4318 0.3302)
						)
						(arc
							(start 0.4318 -0.3302)
							(mid 0.402042 -0.402042)
							(end 0.3302 -0.4318)
						)
					)
					(width 0)
					(fill yes)
				)
			)
		)
		(pad "2" smd custom
			(at 0 0.762)
			(size 0.2159 0.2159)
			(layers "F.Cu" "F.Mask" "F.Paste")
			(net "DRV_ACT_13")
			(options
				(clearance outline)
				(anchor circle)
			)
			(primitives
				(gr_poly
					(pts
						(arc
							(start -0.3302 -0.4318)
							(mid -0.402042 -0.402042)
							(end -0.4318 -0.3302)
						)
						(arc
							(start -0.4318 0.3302)
							(mid -0.402042 0.402042)
							(end -0.3302 0.4318)
						)
						(arc
							(start 0.3302 0.4318)
							(mid 0.402042 0.402042)
							(end 0.4318 0.3302)
						)
						(arc
							(start 0.4318 -0.3302)
							(mid 0.402042 -0.402042)
							(end 0.3302 -0.4318)
						)
					)
					(width 0)
					(fill yes)
				)
			)
		)
	)
	(footprint ""
		(layer "F.Cu")
		(at 447.166238 -255.778254 -90)
		(property "Reference" "R1251"
			(at 0 0 270)
			(layer "F.SilkS")
			(hide yes)
			(effects
				(font
					(size 1.27 1.27)
				)
			)
		)
		(property "Value" "200KR2F-L-GP"
			(at 0.064008 -3.993896 270)
			(unlocked yes)
			(layer "F.Fab")
			(hide yes)
			(effects
				(font
					(size 1.016 1.016)
					(thickness 0.1524)
				)
			)
		)
		(property "Device Type" "R402H16"
			(at 0.064008 -5.517896 270)
			(unlocked yes)
			(layer "F.Fab")
			(hide yes)
			(effects
				(font
					(size 1.016 1.016)
					(thickness 0.1524)
				)
			)
		)
		(duplicate_pad_numbers_are_jumpers no)
		(fp_line
			(start -0.508 -0.9398)
			(end -0.508 0.9398)
			(stroke
				(width 0.1524)
				(type default)
			)
			(layer "F.SilkS")
		)
		(fp_line
			(start 0.508 -0.9398)
			(end -0.508 -0.9398)
			(stroke
				(width 0.1524)
				(type default)
			)
			(layer "F.SilkS")
		)
		(fp_rect
			(start -0.508 0.9398)
			(end 0.508 -0.9398)
			(stroke
				(width 0)
				(type default)
			)
			(fill no)
			(layer "F.CrtYd")
		)
		(fp_rect
			(start -0.508 0.9398)
			(end 0.508 -0.9398)
			(stroke
				(width 0)
				(type default)
			)
			(fill no)
			(layer "F.Fab")
		)
		(pad "1" smd custom
			(at 0 -0.4445 270)
			(size 0.1397 0.1397)
			(layers "F.Cu" "F.Mask" "F.Paste")
			(net "P5V_C_MODE")
			(options
				(clearance outline)
				(anchor circle)
			)
			(primitives
				(gr_poly
					(pts
						(arc
							(start -0.1778 -0.2794)
							(mid -0.249642 -0.249642)
							(end -0.2794 -0.1778)
						)
						(arc
							(start -0.2794 0.1778)
							(mid -0.249642 0.249642)
							(end -0.1778 0.2794)
						)
						(arc
							(start 0.1778 0.2794)
							(mid 0.249642 0.249642)
							(end 0.2794 0.1778)
						)
						(arc
							(start 0.2794 -0.1778)
							(mid 0.249642 -0.249642)
							(end 0.1778 -0.2794)
						)
					)
					(width 0)
					(fill yes)
				)
			)
		)
		(pad "2" smd custom
			(at 0 0.4445 270)
			(size 0.1397 0.1397)
			(layers "F.Cu" "F.Mask" "F.Paste")
			(net "P5V_A_3_PGOOD")
			(options
				(clearance outline)
				(anchor circle)
			)
			(primitives
				(gr_poly
					(pts
						(arc
							(start -0.1778 -0.2794)
							(mid -0.249642 -0.249642)
							(end -0.2794 -0.1778)
						)
						(arc
							(start -0.2794 0.1778)
							(mid -0.249642 0.249642)
							(end -0.1778 0.2794)
						)
						(arc
							(start 0.1778 0.2794)
							(mid 0.249642 0.249642)
							(end 0.2794 0.1778)
						)
						(arc
							(start 0.2794 -0.1778)
							(mid 0.249642 -0.249642)
							(end 0.1778 -0.2794)
						)
					)
					(width 0)
					(fill yes)
				)
			)
		)
	)
	(footprint ""
		(layer "F.Cu")
		(at 127.113284 -159.219392 90)
		(property "Reference" "C233"
			(at 0 0 90)
			(layer "F.SilkS")
			(hide yes)
			(effects
				(font
					(size 1.27 1.27)
				)
			)
		)
		(property "Value" "SCD01U16V1KX-GP"
			(at -2.8321 -1.7399 90)
			(unlocked yes)
			(layer "F.Fab")
			(hide yes)
			(effects
				(font
					(size 1.016 1.016)
					(thickness 0.1524)
				)
			)
		)
		(property "Device Type" "C0201H13"
			(at -2.8321 -3.2639 90)
			(unlocked yes)
			(layer "F.Fab")
			(hide yes)
			(effects
				(font
					(size 1.016 1.016)
					(thickness 0.1524)
				)
			)
		)
		(duplicate_pad_numbers_are_jumpers no)
		(fp_rect
			(start -0.2794 0.6477)
			(end 0.2794 -0.6477)
			(stroke
				(width 0)
				(type default)
			)
			(fill no)
			(layer "F.CrtYd")
		)
		(fp_rect
			(start -0.2794 0.6477)
			(end 0.2794 -0.6477)
			(stroke
				(width 0)
				(type default)
			)
			(fill no)
			(layer "F.Fab")
		)
		(pad "1" smd custom
			(at 0 -0.2794 90)
			(size 0.0762 0.0762)
			(layers "F.Cu" "F.Mask" "F.Paste")
			(net "SAS_HDD_RX_N15")
			(options
				(clearance outline)
				(anchor circle)
			)
			(primitives
				(gr_poly
					(pts
						(arc
							(start 0.1524 -0.127)
							(mid 0.137521 -0.162921)
							(end 0.1016 -0.1778)
						)
						(arc
							(start -0.1016 -0.1778)
							(mid -0.137521 -0.162921)
							(end -0.1524 -0.127)
						)
						(arc
							(start -0.1524 0.127)
							(mid -0.137521 0.162921)
							(end -0.1016 0.1778)
						)
						(arc
							(start 0.1016 0.1778)
							(mid 0.137521 0.162921)
							(end 0.1524 0.127)
						)
					)
					(width 0)
					(fill yes)
				)
			)
		)
		(pad "2" smd custom
			(at 0 0.2794 90)
			(size 0.0762 0.0762)
			(layers "F.Cu" "F.Mask" "F.Paste")
			(net "PHY_SCC_A_TO_DRV_A_15_DN")
			(options
				(clearance outline)
				(anchor circle)
			)
			(primitives
				(gr_poly
					(pts
						(arc
							(start 0.1524 -0.127)
							(mid 0.137521 -0.162921)
							(end 0.1016 -0.1778)
						)
						(arc
							(start -0.1016 -0.1778)
							(mid -0.137521 -0.162921)
							(end -0.1524 -0.127)
						)
						(arc
							(start -0.1524 0.127)
							(mid -0.137521 0.162921)
							(end -0.1016 0.1778)
						)
						(arc
							(start 0.1016 0.1778)
							(mid 0.137521 0.162921)
							(end 0.1524 0.127)
						)
					)
					(width 0)
					(fill yes)
				)
			)
		)
	)
	(footprint ""
		(layer "F.Cu")
		(at 46.265846 -64.683894 -90)
		(property "Reference" "C370"
			(at 0 0 270)
			(layer "F.SilkS")
			(hide yes)
			(effects
				(font
					(size 1.27 1.27)
				)
			)
		)
		(property "Value" "SC4D7U25V5KX-1-GP"
			(at -0.0762 -6.1214 270)
			(unlocked yes)
			(layer "F.Fab")
			(hide yes)
			(effects
				(font
					(size 1.016 1.016)
					(thickness 0.1524)
				)
			)
		)
		(property "Device Type" "C805H58"
			(at -0.0762 -8.1534 270)
			(unlocked yes)
			(layer "F.Fab")
			(hide yes)
			(effects
				(font
					(size 1.016 1.016)
					(thickness 0.1524)
				)
			)
		)
		(duplicate_pad_numbers_are_jumpers no)
		(fp_line
			(start 0.635 0)
			(end -0.635 0)
			(stroke
				(width 0.508)
				(type default)
			)
			(layer "F.SilkS")
		)
		(fp_rect
			(start -0.9652 1.778)
			(end 0.9652 -1.778)
			(stroke
				(width 0)
				(type default)
			)
			(fill no)
			(layer "F.CrtYd")
		)
		(fp_poly
			(pts
				(xy -0.9652 -1.778) (xy 0.9652 -1.778) (xy 0.9652 1.778) (xy -0.9652 1.778)
			)
			(stroke
				(width 0)
				(type default)
			)
			(fill no)
			(layer "F.Fab")
		)
		(pad "1" smd rect
			(at 0 -0.9652 270)
			(size 1.397 1.143)
			(layers "F.Cu" "F.Mask" "F.Paste")
			(net "P12V_HDD25")
		)
		(pad "2" smd rect
			(at 0 0.9652 270)
			(size 1.397 1.143)
			(layers "F.Cu" "F.Mask" "F.Paste")
			(net "GND")
		)
	)
)
